(kicad_pcb
	(version 20260206)
	(generator "pcbnew")
	(generator_version "10.0")
	(general
		(thickness 1.6)
		(legacy_teardrops no)
	)
	(paper "A4")
	(title_block
		(title "01162023_DA0F0TEBIF0_F0T_Expander_BD_F_brd_V02_OCP.brd")
		(comment 1 "Grand Teton / footprints 3010-3015 of 9728")
	)
	(layers
		(0 "F.Cu" signal "TOP")
		(4 "In1.Cu" signal "GND")
		(6 "In2.Cu" signal "VCC")
		(8 "In3.Cu" signal "VCC1")
		(10 "In4.Cu" signal "GND1")
		(12 "In5.Cu" signal "IN1")
		(14 "In6.Cu" signal "GND2")
		(16 "In7.Cu" signal "IN2")
		(18 "In8.Cu" signal "GND3")
		(20 "In9.Cu" signal "IN3")
		(22 "In10.Cu" signal "GND4")
		(24 "In11.Cu" signal "IN4")
		(26 "In12.Cu" signal "GND5")
		(28 "In13.Cu" signal "IN5")
		(30 "In14.Cu" signal "GND6")
		(32 "In15.Cu" signal "IN6")
		(34 "In16.Cu" signal "GND7")
		(2 "B.Cu" signal "BOTTOM")
		(9 "F.Adhes" user "F.Adhesive")
		(11 "B.Adhes" user "B.Adhesive")
		(13 "F.Paste" user "Package Geometry/Pastemask Top")
		(15 "B.Paste" user "Package Geometry/Pastemask Bottom")
		(5 "F.SilkS" user "Ref Des/Silkscreen Top")
		(7 "B.SilkS" user "Ref Des/Silkscreen Bottom")
		(1 "F.Mask" user "Board Geometry/Soldermask Top")
		(3 "B.Mask" user "Board Geometry/Soldermask Bottom")
		(17 "Dwgs.User" user "User.Drawings")
		(19 "Cmts.User" user "User.Comments")
		(21 "Eco1.User" user "User.Eco1")
		(23 "Eco2.User" user "User.Eco2")
		(25 "Edge.Cuts" user "Board Geometry/Outline")
		(27 "Margin" user)
		(31 "F.CrtYd" user "Package Geometry/Place Bound Top")
		(29 "B.CrtYd" user "Package Geometry/Place Bound Bottom")
		(35 "F.Fab" user "Ref Des/Assembly Top")
		(33 "B.Fab" user "Ref Des/Assembly Bottom")
	)
	(footprint ""
		(layer "F.Cu")
		(at 2.614168 -24.945594 90)
		(property "Reference" "R1637"
			(at 0 0 90)
			(layer "F.SilkS")
			(hide yes)
			(effects
				(font
					(size 1.27 1.27)
				)
			)
		)
		(property "Value" ""
			(at 0 0 90)
			(layer "F.Fab")
			(effects
				(font
					(size 1.27 1.27)
				)
			)
		)
		(duplicate_pad_numbers_are_jumpers no)
		(fp_line
			(start 0.7874 -0.4064)
			(end 0.7874 0.4064)
			(stroke
				(width 0.1524)
				(type default)
			)
			(layer "F.SilkS")
		)
		(fp_line
			(start -0.7874 -0.4064)
			(end 0.7874 -0.4064)
			(stroke
				(width 0.1524)
				(type default)
			)
			(layer "F.SilkS")
		)
		(fp_line
			(start 0.7874 0.4064)
			(end -0.7874 0.4064)
			(stroke
				(width 0.1524)
				(type default)
			)
			(layer "F.SilkS")
		)
		(fp_line
			(start -0.7874 0.4064)
			(end -0.7874 -0.4064)
			(stroke
				(width 0.1524)
				(type default)
			)
			(layer "F.SilkS")
		)
		(fp_line
			(start -0.12065 -0.305054)
			(end -0.12065 -0.2794)
			(stroke
				(width 0.1)
				(type default)
			)
			(layer "F.Fab")
		)
		(fp_line
			(start -0.67945 -0.305054)
			(end -0.12065 -0.305054)
			(stroke
				(width 0.1)
				(type default)
			)
			(layer "F.Fab")
		)
		(fp_line
			(start 0.67945 -0.3048)
			(end 0.67945 0.3048)
			(stroke
				(width 0.1)
				(type default)
			)
			(layer "F.Fab")
		)
		(fp_line
			(start 0.12065 -0.3048)
			(end 0.67945 -0.3048)
			(stroke
				(width 0.1)
				(type default)
			)
			(layer "F.Fab")
		)
		(fp_line
			(start 0.12065 -0.2794)
			(end 0.12065 -0.3048)
			(stroke
				(width 0.1)
				(type default)
			)
			(layer "F.Fab")
		)
		(fp_line
			(start -0.12065 -0.2794)
			(end 0.12065 -0.2794)
			(stroke
				(width 0.1)
				(type default)
			)
			(layer "F.Fab")
		)
		(fp_line
			(start 0.120396 0.2794)
			(end -0.12065 0.2794)
			(stroke
				(width 0.1)
				(type default)
			)
			(layer "F.Fab")
		)
		(fp_line
			(start -0.12065 0.2794)
			(end -0.12065 0.3048)
			(stroke
				(width 0.1)
				(type default)
			)
			(layer "F.Fab")
		)
		(fp_line
			(start 0.67945 0.3048)
			(end 0.120396 0.3048)
			(stroke
				(width 0.1)
				(type default)
			)
			(layer "F.Fab")
		)
		(fp_line
			(start 0.120396 0.3048)
			(end 0.120396 0.2794)
			(stroke
				(width 0.1)
				(type default)
			)
			(layer "F.Fab")
		)
		(fp_line
			(start -0.12065 0.3048)
			(end -0.67945 0.3048)
			(stroke
				(width 0.1)
				(type default)
			)
			(layer "F.Fab")
		)
		(fp_line
			(start -0.67945 0.3048)
			(end -0.67945 -0.305054)
			(stroke
				(width 0.1)
				(type default)
			)
			(layer "F.Fab")
		)
		(pad "1" smd circle
			(at -0.40005 0 90)
			(size 0 0)
			(layers "F.Cu" "F.Mask" "F.Paste")
			(net "SMB_ISO_SSD0_R_SCL")
		)
		(pad "2" smd circle
			(at 0.40005 0 90)
			(size 0 0)
			(layers "F.Cu" "F.Mask" "F.Paste")
			(net "SMB_ISO_SSD0_SCL")
		)
	)
	(footprint ""
		(layer "F.Cu")
		(at 222.482664 -204.44206 90)
		(property "Reference" "R5536"
			(at 0 0 90)
			(layer "F.SilkS")
			(hide yes)
			(effects
				(font
					(size 1.27 1.27)
				)
			)
		)
		(property "Value" ""
			(at 0 0 90)
			(layer "F.Fab")
			(effects
				(font
					(size 1.27 1.27)
				)
			)
		)
		(duplicate_pad_numbers_are_jumpers no)
		(fp_line
			(start 0.7874 -0.4064)
			(end 0.7874 0.4064)
			(stroke
				(width 0.1524)
				(type default)
			)
			(layer "F.SilkS")
		)
		(fp_line
			(start -0.7874 -0.4064)
			(end 0.7874 -0.4064)
			(stroke
				(width 0.1524)
				(type default)
			)
			(layer "F.SilkS")
		)
		(fp_line
			(start 0.7874 0.4064)
			(end -0.7874 0.4064)
			(stroke
				(width 0.1524)
				(type default)
			)
			(layer "F.SilkS")
		)
		(fp_line
			(start -0.7874 0.4064)
			(end -0.7874 -0.4064)
			(stroke
				(width 0.1524)
				(type default)
			)
			(layer "F.SilkS")
		)
		(fp_line
			(start -0.12065 -0.305054)
			(end -0.12065 -0.2794)
			(stroke
				(width 0.1)
				(type default)
			)
			(layer "F.Fab")
		)
		(fp_line
			(start -0.67945 -0.305054)
			(end -0.12065 -0.305054)
			(stroke
				(width 0.1)
				(type default)
			)
			(layer "F.Fab")
		)
		(fp_line
			(start 0.67945 -0.3048)
			(end 0.67945 0.3048)
			(stroke
				(width 0.1)
				(type default)
			)
			(layer "F.Fab")
		)
		(fp_line
			(start 0.12065 -0.3048)
			(end 0.67945 -0.3048)
			(stroke
				(width 0.1)
				(type default)
			)
			(layer "F.Fab")
		)
		(fp_line
			(start 0.12065 -0.2794)
			(end 0.12065 -0.3048)
			(stroke
				(width 0.1)
				(type default)
			)
			(layer "F.Fab")
		)
		(fp_line
			(start -0.12065 -0.2794)
			(end 0.12065 -0.2794)
			(stroke
				(width 0.1)
				(type default)
			)
			(layer "F.Fab")
		)
		(fp_line
			(start 0.120396 0.2794)
			(end -0.12065 0.2794)
			(stroke
				(width 0.1)
				(type default)
			)
			(layer "F.Fab")
		)
		(fp_line
			(start -0.12065 0.2794)
			(end -0.12065 0.3048)
			(stroke
				(width 0.1)
				(type default)
			)
			(layer "F.Fab")
		)
		(fp_line
			(start 0.67945 0.3048)
			(end 0.120396 0.3048)
			(stroke
				(width 0.1)
				(type default)
			)
			(layer "F.Fab")
		)
		(fp_line
			(start 0.120396 0.3048)
			(end 0.120396 0.2794)
			(stroke
				(width 0.1)
				(type default)
			)
			(layer "F.Fab")
		)
		(fp_line
			(start -0.12065 0.3048)
			(end -0.67945 0.3048)
			(stroke
				(width 0.1)
				(type default)
			)
			(layer "F.Fab")
		)
		(fp_line
			(start -0.67945 0.3048)
			(end -0.67945 -0.305054)
			(stroke
				(width 0.1)
				(type default)
			)
			(layer "F.Fab")
		)
		(pad "1" smd circle
			(at -0.40005 0 90)
			(size 0 0)
			(layers "F.Cu" "F.Mask" "F.Paste")
			(net "P3V3_AUX")
		)
		(pad "2" smd circle
			(at 0.40005 0 90)
			(size 0 0)
			(layers "F.Cu" "F.Mask" "F.Paste")
			(net "SGPIO_BIC_CLK")
		)
	)
	(footprint ""
		(layer "F.Cu")
		(at 259.130038 -287.604708 -90)
		(property "Reference" "C3365"
			(at 0 0 270)
			(layer "F.SilkS")
			(hide yes)
			(effects
				(font
					(size 1.27 1.27)
				)
			)
		)
		(property "Value" ""
			(at 0 0 270)
			(layer "F.Fab")
			(effects
				(font
					(size 1.27 1.27)
				)
			)
		)
		(duplicate_pad_numbers_are_jumpers no)
		(fp_line
			(start -1.2954 0.5842)
			(end -1.2954 -0.5842)
			(stroke
				(width 0.1524)
				(type default)
			)
			(layer "F.SilkS")
		)
		(fp_line
			(start 1.2954 0.5842)
			(end -1.2954 0.5842)
			(stroke
				(width 0.1524)
				(type default)
			)
			(layer "F.SilkS")
		)
		(fp_line
			(start -1.2954 -0.5842)
			(end 1.2954 -0.5842)
			(stroke
				(width 0.1524)
				(type default)
			)
			(layer "F.SilkS")
		)
		(fp_line
			(start 1.2954 -0.5842)
			(end 1.2954 0.5842)
			(stroke
				(width 0.1524)
				(type default)
			)
			(layer "F.SilkS")
		)
		(fp_line
			(start -0.8636 0.4572)
			(end -0.8636 0.4064)
			(stroke
				(width 0.1)
				(type default)
			)
			(layer "F.Fab")
		)
		(fp_line
			(start 0.8636 0.4572)
			(end -0.8636 0.4572)
			(stroke
				(width 0.1)
				(type default)
			)
			(layer "F.Fab")
		)
		(fp_line
			(start -1.1938 0.4064)
			(end -1.1938 -0.4064)
			(stroke
				(width 0.1)
				(type default)
			)
			(layer "F.Fab")
		)
		(fp_line
			(start -0.8636 0.4064)
			(end -1.1938 0.4064)
			(stroke
				(width 0.1)
				(type default)
			)
			(layer "F.Fab")
		)
		(fp_line
			(start 0.8636 0.4064)
			(end 0.8636 0.4572)
			(stroke
				(width 0.1)
				(type default)
			)
			(layer "F.Fab")
		)
		(fp_line
			(start 1.1938 0.4064)
			(end 0.8636 0.4064)
			(stroke
				(width 0.1)
				(type default)
			)
			(layer "F.Fab")
		)
		(fp_line
			(start -1.1938 -0.4064)
			(end -0.8636 -0.4064)
			(stroke
				(width 0.1)
				(type default)
			)
			(layer "F.Fab")
		)
		(fp_line
			(start -0.8636 -0.4064)
			(end -0.8636 -0.4572)
			(stroke
				(width 0.1)
				(type default)
			)
			(layer "F.Fab")
		)
		(fp_line
			(start 0.8636 -0.4064)
			(end 1.1938 -0.4064)
			(stroke
				(width 0.1)
				(type default)
			)
			(layer "F.Fab")
		)
		(fp_line
			(start 1.1938 -0.4064)
			(end 1.1938 0.4064)
			(stroke
				(width 0.1)
				(type default)
			)
			(layer "F.Fab")
		)
		(fp_line
			(start -0.8636 -0.4572)
			(end 0.8636 -0.4572)
			(stroke
				(width 0.1)
				(type default)
			)
			(layer "F.Fab")
		)
		(fp_line
			(start 0.8636 -0.4572)
			(end 0.8636 -0.4064)
			(stroke
				(width 0.1)
				(type default)
			)
			(layer "F.Fab")
		)
		(pad "1" smd rect
			(at -0.7366 0 180)
			(size 0.7112 0.8128)
			(layers "F.Cu" "F.Mask" "F.Paste")
			(net "P1V8_PLL0_PEX2")
		)
		(pad "2" smd rect
			(at 0.7366 0 180)
			(size 0.7112 0.8128)
			(layers "F.Cu" "F.Mask" "F.Paste")
			(net "GND")
		)
	)
	(footprint ""
		(layer "F.Cu")
		(at 404.18004 -139.6492)
		(property "Reference" "R312"
			(at 0 0 0)
			(layer "F.SilkS")
			(hide yes)
			(effects
				(font
					(size 1.27 1.27)
				)
			)
		)
		(property "Value" ""
			(at 0 0 0)
			(layer "F.Fab")
			(effects
				(font
					(size 1.27 1.27)
				)
			)
		)
		(duplicate_pad_numbers_are_jumpers no)
		(fp_line
			(start -0.7874 -0.4064)
			(end 0.7874 -0.4064)
			(stroke
				(width 0.1524)
				(type default)
			)
			(layer "F.SilkS")
		)
		(fp_line
			(start -0.7874 0.4064)
			(end -0.7874 -0.4064)
			(stroke
				(width 0.1524)
				(type default)
			)
			(layer "F.SilkS")
		)
		(fp_line
			(start 0.7874 -0.4064)
			(end 0.7874 0.4064)
			(stroke
				(width 0.1524)
				(type default)
			)
			(layer "F.SilkS")
		)
		(fp_line
			(start 0.7874 0.4064)
			(end -0.7874 0.4064)
			(stroke
				(width 0.1524)
				(type default)
			)
			(layer "F.SilkS")
		)
		(fp_line
			(start -0.67945 -0.305054)
			(end -0.12065 -0.305054)
			(stroke
				(width 0.1)
				(type default)
			)
			(layer "F.Fab")
		)
		(fp_line
			(start -0.67945 0.3048)
			(end -0.67945 -0.305054)
			(stroke
				(width 0.1)
				(type default)
			)
			(layer "F.Fab")
		)
		(fp_line
			(start -0.12065 -0.305054)
			(end -0.12065 -0.2794)
			(stroke
				(width 0.1)
				(type default)
			)
			(layer "F.Fab")
		)
		(fp_line
			(start -0.12065 -0.2794)
			(end 0.12065 -0.2794)
			(stroke
				(width 0.1)
				(type default)
			)
			(layer "F.Fab")
		)
		(fp_line
			(start -0.12065 0.2794)
			(end -0.12065 0.3048)
			(stroke
				(width 0.1)
				(type default)
			)
			(layer "F.Fab")
		)
		(fp_line
			(start -0.12065 0.3048)
			(end -0.67945 0.3048)
			(stroke
				(width 0.1)
				(type default)
			)
			(layer "F.Fab")
		)
		(fp_line
			(start 0.120396 0.2794)
			(end -0.12065 0.2794)
			(stroke
				(width 0.1)
				(type default)
			)
			(layer "F.Fab")
		)
		(fp_line
			(start 0.120396 0.3048)
			(end 0.120396 0.2794)
			(stroke
				(width 0.1)
				(type default)
			)
			(layer "F.Fab")
		)
		(fp_line
			(start 0.12065 -0.3048)
			(end 0.67945 -0.3048)
			(stroke
				(width 0.1)
				(type default)
			)
			(layer "F.Fab")
		)
		(fp_line
			(start 0.12065 -0.2794)
			(end 0.12065 -0.3048)
			(stroke
				(width 0.1)
				(type default)
			)
			(layer "F.Fab")
		)
		(fp_line
			(start 0.67945 -0.3048)
			(end 0.67945 0.3048)
			(stroke
				(width 0.1)
				(type default)
			)
			(layer "F.Fab")
		)
		(fp_line
			(start 0.67945 0.3048)
			(end 0.120396 0.3048)
			(stroke
				(width 0.1)
				(type default)
			)
			(layer "F.Fab")
		)
		(pad "1" smd circle
			(at -0.40005 0)
			(size 0 0)
			(layers "F.Cu" "F.Mask" "F.Paste")
			(net "PRSNTB2_NIC6_N")
		)
		(pad "2" smd circle
			(at 0.40005 0)
			(size 0 0)
			(layers "F.Cu" "F.Mask" "F.Paste")
			(net "P3V3_AUX")
		)
	)
	(footprint ""
		(layer "F.Cu")
		(at 355.913436 -137.344404 180)
		(property "Reference" "PR202"
			(at 0 0 180)
			(layer "F.SilkS")
			(hide yes)
			(effects
				(font
					(size 1.27 1.27)
				)
			)
		)
		(property "Value" ""
			(at 0 0 180)
			(layer "F.Fab")
			(effects
				(font
					(size 1.27 1.27)
				)
			)
		)
		(duplicate_pad_numbers_are_jumpers no)
		(fp_line
			(start 0.7874 0.4064)
			(end -0.7874 0.4064)
			(stroke
				(width 0.1524)
				(type default)
			)
			(layer "F.SilkS")
		)
		(fp_line
			(start 0.7874 -0.4064)
			(end 0.7874 0.4064)
			(stroke
				(width 0.1524)
				(type default)
			)
			(layer "F.SilkS")
		)
		(fp_line
			(start -0.7874 0.4064)
			(end -0.7874 -0.4064)
			(stroke
				(width 0.1524)
				(type default)
			)
			(layer "F.SilkS")
		)
		(fp_line
			(start -0.7874 -0.4064)
			(end 0.7874 -0.4064)
			(stroke
				(width 0.1524)
				(type default)
			)
			(layer "F.SilkS")
		)
		(fp_line
			(start 0.67945 0.3048)
			(end 0.120396 0.3048)
			(stroke
				(width 0.1)
				(type default)
			)
			(layer "F.Fab")
		)
		(fp_line
			(start 0.67945 -0.3048)
			(end 0.67945 0.3048)
			(stroke
				(width 0.1)
				(type default)
			)
			(layer "F.Fab")
		)
		(fp_line
			(start 0.12065 -0.2794)
			(end 0.12065 -0.3048)
			(stroke
				(width 0.1)
				(type default)
			)
			(layer "F.Fab")
		)
		(fp_line
			(start 0.12065 -0.3048)
			(end 0.67945 -0.3048)
			(stroke
				(width 0.1)
				(type default)
			)
			(layer "F.Fab")
		)
		(fp_line
			(start 0.120396 0.3048)
			(end 0.120396 0.2794)
			(stroke
				(width 0.1)
				(type default)
			)
			(layer "F.Fab")
		)
		(fp_line
			(start 0.120396 0.2794)
			(end -0.12065 0.2794)
			(stroke
				(width 0.1)
				(type default)
			)
			(layer "F.Fab")
		)
		(fp_line
			(start -0.12065 0.3048)
			(end -0.67945 0.3048)
			(stroke
				(width 0.1)
				(type default)
			)
			(layer "F.Fab")
		)
		(fp_line
			(start -0.12065 0.2794)
			(end -0.12065 0.3048)
			(stroke
				(width 0.1)
				(type default)
			)
			(layer "F.Fab")
		)
		(fp_line
			(start -0.12065 -0.2794)
			(end 0.12065 -0.2794)
			(stroke
				(width 0.1)
				(type default)
			)
			(layer "F.Fab")
		)
		(fp_line
			(start -0.12065 -0.305054)
			(end -0.12065 -0.2794)
			(stroke
				(width 0.1)
				(type default)
			)
			(layer "F.Fab")
		)
		(fp_line
			(start -0.67945 0.3048)
			(end -0.67945 -0.305054)
			(stroke
				(width 0.1)
				(type default)
			)
			(layer "F.Fab")
		)
		(fp_line
			(start -0.67945 -0.305054)
			(end -0.12065 -0.305054)
			(stroke
				(width 0.1)
				(type default)
			)
			(layer "F.Fab")
		)
		(pad "1" smd circle
			(at -0.40005 0 180)
			(size 0 0)
			(layers "F.Cu" "F.Mask" "F.Paste")
			(net "P12V_NIC6_OCP")
		)
		(pad "2" smd circle
			(at 0.40005 0 180)
			(size 0 0)
			(layers "F.Cu" "F.Mask" "F.Paste")
			(net "GND")
		)
	)
	(footprint ""
		(layer "F.Cu")
		(at 80.828388 -32.820356 -90)
		(property "Reference" "R5879"
			(at 0 0 270)
			(layer "F.SilkS")
			(hide yes)
			(effects
				(font
					(size 1.27 1.27)
				)
			)
		)
		(property "Value" ""
			(at 0 0 270)
			(layer "F.Fab")
			(effects
				(font
					(size 1.27 1.27)
				)
			)
		)
		(duplicate_pad_numbers_are_jumpers no)
		(fp_line
			(start -0.7874 0.4064)
			(end -0.7874 -0.4064)
			(stroke
				(width 0.1524)
				(type default)
			)
			(layer "F.SilkS")
		)
		(fp_line
			(start 0.7874 0.4064)
			(end -0.7874 0.4064)
			(stroke
				(width 0.1524)
				(type default)
			)
			(layer "F.SilkS")
		)
		(fp_line
			(start -0.7874 -0.4064)
			(end 0.7874 -0.4064)
			(stroke
				(width 0.1524)
				(type default)
			)
			(layer "F.SilkS")
		)
		(fp_line
			(start 0.7874 -0.4064)
			(end 0.7874 0.4064)
			(stroke
				(width 0.1524)
				(type default)
			)
			(layer "F.SilkS")
		)
		(fp_line
			(start -0.67945 0.3048)
			(end -0.67945 -0.305054)
			(stroke
				(width 0.1)
				(type default)
			)
			(layer "F.Fab")
		)
		(fp_line
			(start -0.12065 0.3048)
			(end -0.67945 0.3048)
			(stroke
				(width 0.1)
				(type default)
			)
			(layer "F.Fab")
		)
		(fp_line
			(start 0.120396 0.3048)
			(end 0.120396 0.2794)
			(stroke
				(width 0.1)
				(type default)
			)
			(layer "F.Fab")
		)
		(fp_line
			(start 0.67945 0.3048)
			(end 0.120396 0.3048)
			(stroke
				(width 0.1)
				(type default)
			)
			(layer "F.Fab")
		)
		(fp_line
			(start -0.12065 0.2794)
			(end -0.12065 0.3048)
			(stroke
				(width 0.1)
				(type default)
			)
			(layer "F.Fab")
		)
		(fp_line
			(start 0.120396 0.2794)
			(end -0.12065 0.2794)
			(stroke
				(width 0.1)
				(type default)
			)
			(layer "F.Fab")
		)
		(fp_line
			(start -0.12065 -0.2794)
			(end 0.12065 -0.2794)
			(stroke
				(width 0.1)
				(type default)
			)
			(layer "F.Fab")
		)
		(fp_line
			(start 0.12065 -0.2794)
			(end 0.12065 -0.3048)
			(stroke
				(width 0.1)
				(type default)
			)
			(layer "F.Fab")
		)
		(fp_line
			(start 0.12065 -0.3048)
			(end 0.67945 -0.3048)
			(stroke
				(width 0.1)
				(type default)
			)
			(layer "F.Fab")
		)
		(fp_line
			(start 0.67945 -0.3048)
			(end 0.67945 0.3048)
			(stroke
				(width 0.1)
				(type default)
			)
			(layer "F.Fab")
		)
		(fp_line
			(start -0.67945 -0.305054)
			(end -0.12065 -0.305054)
			(stroke
				(width 0.1)
				(type default)
			)
			(layer "F.Fab")
		)
		(fp_line
			(start -0.12065 -0.305054)
			(end -0.12065 -0.2794)
			(stroke
				(width 0.1)
				(type default)
			)
			(layer "F.Fab")
		)
		(pad "1" smd circle
			(at -0.40005 0 270)
			(size 0 0)
			(layers "F.Cu" "F.Mask" "F.Paste")
			(net "SSD3_AUX_P3V3_EN_R")
		)
		(pad "2" smd circle
			(at 0.40005 0 270)
			(size 0 0)
			(layers "F.Cu" "F.Mask" "F.Paste")
			(net "P3V3_SSD3_CO_EN")
		)
	)
)
